(kicad_pcb
	(version 20260206)
	(generator "pcbnew")
	(generator_version "10.0")
	(general
		(thickness 1.6)
		(legacy_teardrops no)
	)
	(paper "A4")
	(title_block
		(title "pdpb — Lightning_PDPB_BRD.brd")
		(comment 1 "Lightning (Wiwynn / Facebook NVMe JBOF) / footprints 165-171 of 1140")
	)
	(layers
		(0 "F.Cu" signal "TOP")
		(4 "In1.Cu" signal "L2GND")
		(6 "In2.Cu" signal "L3")
		(8 "In3.Cu" signal "L4VCC")
		(10 "In4.Cu" signal "L5VCC")
		(12 "In5.Cu" signal "L6")
		(14 "In6.Cu" signal "L7GND")
		(2 "B.Cu" signal "BOTTOM")
		(9 "F.Adhes" user "F.Adhesive")
		(11 "B.Adhes" user "B.Adhesive")
		(13 "F.Paste" user "Package Geometry/Pastemask Top")
		(15 "B.Paste" user "Package Geometry/Pastemask Bottom")
		(5 "F.SilkS" user "Ref Des/Silkscreen Top")
		(7 "B.SilkS" user "Ref Des/Silkscreen Bottom")
		(1 "F.Mask" user "Board Geometry/Soldermask Top")
		(3 "B.Mask" user "Board Geometry/Soldermask Bottom")
		(17 "Dwgs.User" user "User.Drawings")
		(19 "Cmts.User" user "User.Comments")
		(21 "Eco1.User" user "User.Eco1")
		(23 "Eco2.User" user "User.Eco2")
		(25 "Edge.Cuts" user "Board Geometry/Outline")
		(27 "Margin" user)
		(31 "F.CrtYd" user "Package Geometry/Place Bound Top")
		(29 "B.CrtYd" user "Package Geometry/Place Bound Bottom")
		(35 "F.Fab" user "Ref Des/Assembly Top")
		(33 "B.Fab" user "Ref Des/Assembly Bottom")
	)
	(footprint ""
		(layer "F.Cu")
		(at 24.003 -362.331 -90)
		(property "Reference" "R9435"
			(at 0 0 270)
			(layer "F.SilkS")
			(hide yes)
			(effects
				(font
					(size 1.27 1.27)
				)
			)
		)
		(property "Value" "330R2F-GP"
			(at 0.064008 -3.993896 270)
			(unlocked yes)
			(layer "F.Fab")
			(hide yes)
			(effects
				(font
					(size 1.016 1.016)
					(thickness 0.1524)
				)
			)
		)
		(property "Device Type" "R402H16"
			(at 0.064008 -5.517896 270)
			(unlocked yes)
			(layer "F.Fab")
			(hide yes)
			(effects
				(font
					(size 1.016 1.016)
					(thickness 0.1524)
				)
			)
		)
		(duplicate_pad_numbers_are_jumpers no)
		(fp_line
			(start -0.508 -0.9398)
			(end -0.508 0.9398)
			(stroke
				(width 0.1524)
				(type default)
			)
			(layer "F.SilkS")
		)
		(fp_line
			(start 0.508 -0.9398)
			(end -0.508 -0.9398)
			(stroke
				(width 0.1524)
				(type default)
			)
			(layer "F.SilkS")
		)
		(fp_rect
			(start -0.508 0.9398)
			(end 0.508 -0.9398)
			(stroke
				(width 0)
				(type default)
			)
			(fill no)
			(layer "F.CrtYd")
		)
		(fp_rect
			(start -0.508 0.9398)
			(end 0.508 -0.9398)
			(stroke
				(width 0)
				(type default)
			)
			(fill no)
			(layer "F.Fab")
		)
		(pad "1" smd custom
			(at 0 -0.4445 270)
			(size 0.1397 0.1397)
			(layers "F.Cu" "F.Mask" "F.Paste")
			(net "P3V3")
			(options
				(clearance outline)
				(anchor circle)
			)
			(primitives
				(gr_poly
					(pts
						(arc
							(start -0.1778 -0.2794)
							(mid -0.249642 -0.249642)
							(end -0.2794 -0.1778)
						)
						(arc
							(start -0.2794 0.1778)
							(mid -0.249642 0.249642)
							(end -0.1778 0.2794)
						)
						(arc
							(start 0.1778 0.2794)
							(mid 0.249642 0.249642)
							(end 0.2794 0.1778)
						)
						(arc
							(start 0.2794 -0.1778)
							(mid 0.249642 -0.249642)
							(end 0.1778 -0.2794)
						)
					)
					(width 0)
					(fill yes)
				)
			)
		)
		(pad "2" smd custom
			(at 0 0.4445 270)
			(size 0.1397 0.1397)
			(layers "F.Cu" "F.Mask" "F.Paste")
			(net "DRV_ATTN_11")
			(options
				(clearance outline)
				(anchor circle)
			)
			(primitives
				(gr_poly
					(pts
						(arc
							(start -0.1778 -0.2794)
							(mid -0.249642 -0.249642)
							(end -0.2794 -0.1778)
						)
						(arc
							(start -0.2794 0.1778)
							(mid -0.249642 0.249642)
							(end -0.1778 0.2794)
						)
						(arc
							(start 0.1778 0.2794)
							(mid 0.249642 0.249642)
							(end 0.2794 0.1778)
						)
						(arc
							(start 0.2794 -0.1778)
							(mid 0.249642 -0.249642)
							(end 0.1778 -0.2794)
						)
					)
					(width 0)
					(fill yes)
				)
			)
		)
	)
	(footprint ""
		(layer "F.Cu")
		(at 35.46475 -101.91115 90)
		(property "Reference" "Q92"
			(at 0 0 90)
			(layer "F.SilkS")
			(hide yes)
			(effects
				(font
					(size 1.27 1.27)
				)
			)
		)
		(property "Value" "2N7002A-7-GP"
			(at 0.127 -8.9662 90)
			(unlocked yes)
			(layer "F.Fab")
			(hide yes)
			(effects
				(font
					(size 1.016 1.016)
					(thickness 0.1524)
				)
			)
		)
		(property "Device Type" "SOT23DGS2D4H48"
			(at 0.127 -10.4902 90)
			(unlocked yes)
			(layer "F.Fab")
			(hide yes)
			(effects
				(font
					(size 1.016 1.016)
					(thickness 0.1524)
				)
			)
		)
		(duplicate_pad_numbers_are_jumpers no)
		(fp_line
			(start 1.651 -1.778)
			(end -1.651 -1.778)
			(stroke
				(width 0.1524)
				(type default)
			)
			(layer "F.SilkS")
		)
		(fp_line
			(start -1.651 -1.778)
			(end -1.651 1.778)
			(stroke
				(width 0.1524)
				(type default)
			)
			(layer "F.SilkS")
		)
		(fp_line
			(start 1.651 1.778)
			(end 1.651 -1.778)
			(stroke
				(width 0.1524)
				(type default)
			)
			(layer "F.SilkS")
		)
		(fp_line
			(start -1.651 1.778)
			(end 1.651 1.778)
			(stroke
				(width 0.1524)
				(type default)
			)
			(layer "F.SilkS")
		)
		(fp_poly
			(pts
				(xy -1.778 1.8796) (xy -1.778 -1.8796) (xy 1.778 -1.8796) (xy 1.778 1.8796)
			)
			(stroke
				(width 0)
				(type default)
			)
			(fill no)
			(layer "F.CrtYd")
		)
		(fp_poly
			(pts
				(xy -1.778 1.8796) (xy -1.778 -1.8796) (xy 1.778 -1.8796) (xy 1.778 1.8796)
			)
			(stroke
				(width 0)
				(type default)
			)
			(fill no)
			(layer "F.Fab")
		)
		(pad "D" smd custom
			(at 0 -0.9525 90)
			(size 0.1905 0.1905)
			(layers "F.Cu" "F.Mask" "F.Paste")
			(net "P12V_MOST13_GATE")
			(options
				(clearance outline)
				(anchor circle)
			)
			(primitives
				(gr_poly
					(pts
						(arc
							(start -0.1778 0.5715)
							(mid -0.321484 0.511984)
							(end -0.381 0.3683)
						)
						(arc
							(start -0.381 -0.3683)
							(mid -0.321484 -0.511984)
							(end -0.1778 -0.5715)
						)
						(arc
							(start 0.1778 -0.5715)
							(mid 0.321484 -0.511984)
							(end 0.381 -0.3683)
						)
						(arc
							(start 0.381 0.3683)
							(mid 0.321484 0.511984)
							(end 0.1778 0.5715)
						)
					)
					(width 0)
					(fill yes)
				)
			)
		)
		(pad "G" smd custom
			(at -0.98425 0.9525 90)
			(size 0.1905 0.1905)
			(layers "F.Cu" "F.Mask" "F.Paste")
			(net "SSD13_PWREN_R")
			(options
				(clearance outline)
				(anchor circle)
			)
			(primitives
				(gr_poly
					(pts
						(arc
							(start -0.1778 0.5715)
							(mid -0.321484 0.511984)
							(end -0.381 0.3683)
						)
						(arc
							(start -0.381 -0.3683)
							(mid -0.321484 -0.511984)
							(end -0.1778 -0.5715)
						)
						(arc
							(start 0.1778 -0.5715)
							(mid 0.321484 -0.511984)
							(end 0.381 -0.3683)
						)
						(arc
							(start 0.381 0.3683)
							(mid 0.321484 0.511984)
							(end 0.1778 0.5715)
						)
					)
					(width 0)
					(fill yes)
				)
			)
		)
		(pad "S" smd custom
			(at 0.98425 0.9525 90)
			(size 0.1905 0.1905)
			(layers "F.Cu" "F.Mask" "F.Paste")
			(net "GND")
			(options
				(clearance outline)
				(anchor circle)
			)
			(primitives
				(gr_poly
					(pts
						(arc
							(start -0.1778 0.5715)
							(mid -0.321484 0.511984)
							(end -0.381 0.3683)
						)
						(arc
							(start -0.381 -0.3683)
							(mid -0.321484 -0.511984)
							(end -0.1778 -0.5715)
						)
						(arc
							(start 0.1778 -0.5715)
							(mid 0.321484 -0.511984)
							(end 0.381 -0.3683)
						)
						(arc
							(start 0.381 0.3683)
							(mid 0.321484 0.511984)
							(end 0.1778 0.5715)
						)
					)
					(width 0)
					(fill yes)
				)
			)
		)
	)
	(footprint ""
		(layer "F.Cu")
		(at 95.504 -92.964)
		(property "Reference" "R9128"
			(at 0 0 0)
			(layer "F.SilkS")
			(hide yes)
			(effects
				(font
					(size 1.27 1.27)
				)
			)
		)
		(property "Value" "27R2F-GP"
			(at 0.064008 -3.993896 0)
			(unlocked yes)
			(layer "F.Fab")
			(hide yes)
			(effects
				(font
					(size 1.016 1.016)
					(thickness 0.1524)
				)
			)
		)
		(property "Device Type" "R402H16"
			(at 0.064008 -5.517896 0)
			(unlocked yes)
			(layer "F.Fab")
			(hide yes)
			(effects
				(font
					(size 1.016 1.016)
					(thickness 0.1524)
				)
			)
		)
		(duplicate_pad_numbers_are_jumpers no)
		(fp_line
			(start -0.508 -0.9398)
			(end -0.508 0.9398)
			(stroke
				(width 0.1524)
				(type default)
			)
			(layer "F.SilkS")
		)
		(fp_line
			(start 0.508 -0.9398)
			(end -0.508 -0.9398)
			(stroke
				(width 0.1524)
				(type default)
			)
			(layer "F.SilkS")
		)
		(fp_rect
			(start -0.508 0.9398)
			(end 0.508 -0.9398)
			(stroke
				(width 0)
				(type default)
			)
			(fill no)
			(layer "F.CrtYd")
		)
		(fp_rect
			(start -0.508 0.9398)
			(end 0.508 -0.9398)
			(stroke
				(width 0)
				(type default)
			)
			(fill no)
			(layer "F.Fab")
		)
		(pad "1" smd custom
			(at 0 -0.4445)
			(size 0.1397 0.1397)
			(layers "F.Cu" "F.Mask" "F.Paste")
			(net "PE_CLK_100M_DR14_2_R_P")
			(options
				(clearance outline)
				(anchor circle)
			)
			(primitives
				(gr_poly
					(pts
						(arc
							(start -0.1778 -0.2794)
							(mid -0.249642 -0.249642)
							(end -0.2794 -0.1778)
						)
						(arc
							(start -0.2794 0.1778)
							(mid -0.249642 0.249642)
							(end -0.1778 0.2794)
						)
						(arc
							(start 0.1778 0.2794)
							(mid 0.249642 0.249642)
							(end 0.2794 0.1778)
						)
						(arc
							(start 0.2794 -0.1778)
							(mid 0.249642 -0.249642)
							(end 0.1778 -0.2794)
						)
					)
					(width 0)
					(fill yes)
				)
			)
		)
		(pad "2" smd custom
			(at 0 0.4445)
			(size 0.1397 0.1397)
			(layers "F.Cu" "F.Mask" "F.Paste")
			(net "PE_CLK100M_DR14_2_P")
			(options
				(clearance outline)
				(anchor circle)
			)
			(primitives
				(gr_poly
					(pts
						(arc
							(start -0.1778 -0.2794)
							(mid -0.249642 -0.249642)
							(end -0.2794 -0.1778)
						)
						(arc
							(start -0.2794 0.1778)
							(mid -0.249642 0.249642)
							(end -0.1778 0.2794)
						)
						(arc
							(start 0.1778 0.2794)
							(mid 0.249642 0.249642)
							(end 0.2794 0.1778)
						)
						(arc
							(start 0.2794 -0.1778)
							(mid 0.249642 -0.249642)
							(end 0.1778 -0.2794)
						)
					)
					(width 0)
					(fill yes)
				)
			)
		)
	)
	(footprint ""
		(layer "F.Cu")
		(at 98.806 -113.665 -90)
		(property "Reference" "C9347"
			(at 0 0 270)
			(layer "F.SilkS")
			(hide yes)
			(effects
				(font
					(size 1.27 1.27)
				)
			)
		)
		(property "Value" "SC1KP50V2KX-1GP"
			(at 1.1811 -2.7051 270)
			(unlocked yes)
			(layer "F.Fab")
			(hide yes)
			(effects
				(font
					(size 1.016 1.016)
					(thickness 0.1524)
				)
			)
		)
		(property "Device Type" "C402H22"
			(at 1.1811 -4.2291 270)
			(unlocked yes)
			(layer "F.Fab")
			(hide yes)
			(effects
				(font
					(size 1.016 1.016)
					(thickness 0.1524)
				)
			)
		)
		(duplicate_pad_numbers_are_jumpers no)
		(fp_rect
			(start -0.4318 0.9525)
			(end 0.4318 -0.9525)
			(stroke
				(width 0)
				(type default)
			)
			(fill no)
			(layer "F.CrtYd")
		)
		(fp_rect
			(start -0.4318 0.9525)
			(end 0.4318 -0.9525)
			(stroke
				(width 0)
				(type default)
			)
			(fill no)
			(layer "F.Fab")
		)
		(pad "1" smd custom
			(at 0 -0.4445 270)
			(size 0.1524 0.1524)
			(layers "F.Cu" "F.Mask" "F.Paste")
			(net "SSD_PRSNT8")
			(options
				(clearance outline)
				(anchor circle)
			)
			(primitives
				(gr_poly
					(pts
						(arc
							(start 0.3048 -0.2032)
							(mid 0.275042 -0.275042)
							(end 0.2032 -0.3048)
						)
						(arc
							(start -0.2032 -0.3048)
							(mid -0.275042 -0.275042)
							(end -0.3048 -0.2032)
						)
						(arc
							(start -0.3048 0.2032)
							(mid -0.275042 0.275042)
							(end -0.2032 0.3048)
						)
						(arc
							(start 0.2032 0.3048)
							(mid 0.275042 0.275042)
							(end 0.3048 0.2032)
						)
					)
					(width 0)
					(fill yes)
				)
			)
		)
		(pad "2" smd custom
			(at 0 0.4445 270)
			(size 0.1524 0.1524)
			(layers "F.Cu" "F.Mask" "F.Paste")
			(net "GND")
			(options
				(clearance outline)
				(anchor circle)
			)
			(primitives
				(gr_poly
					(pts
						(arc
							(start 0.3048 -0.2032)
							(mid 0.275042 -0.275042)
							(end 0.2032 -0.3048)
						)
						(arc
							(start -0.2032 -0.3048)
							(mid -0.275042 -0.275042)
							(end -0.3048 -0.2032)
						)
						(arc
							(start -0.3048 0.2032)
							(mid -0.275042 0.275042)
							(end -0.2032 0.3048)
						)
						(arc
							(start 0.2032 0.3048)
							(mid 0.275042 0.275042)
							(end 0.3048 0.2032)
						)
					)
					(width 0)
					(fill yes)
				)
			)
		)
	)
	(footprint ""
		(layer "F.Cu")
		(at 95.377 -195.834 -90)
		(property "Reference" "R9409"
			(at 0 0 270)
			(layer "F.SilkS")
			(hide yes)
			(effects
				(font
					(size 1.27 1.27)
				)
			)
		)
		(property "Value" "4K7R2J-2-GP"
			(at 0.064008 -3.993896 270)
			(unlocked yes)
			(layer "F.Fab")
			(hide yes)
			(effects
				(font
					(size 1.016 1.016)
					(thickness 0.1524)
				)
			)
		)
		(property "Device Type" "R402H16"
			(at 0.064008 -5.517896 270)
			(unlocked yes)
			(layer "F.Fab")
			(hide yes)
			(effects
				(font
					(size 1.016 1.016)
					(thickness 0.1524)
				)
			)
		)
		(duplicate_pad_numbers_are_jumpers no)
		(fp_line
			(start -0.508 -0.9398)
			(end -0.508 0.9398)
			(stroke
				(width 0.1524)
				(type default)
			)
			(layer "F.SilkS")
		)
		(fp_line
			(start 0.508 -0.9398)
			(end -0.508 -0.9398)
			(stroke
				(width 0.1524)
				(type default)
			)
			(layer "F.SilkS")
		)
		(fp_rect
			(start -0.508 0.9398)
			(end 0.508 -0.9398)
			(stroke
				(width 0)
				(type default)
			)
			(fill no)
			(layer "F.CrtYd")
		)
		(fp_rect
			(start -0.508 0.9398)
			(end 0.508 -0.9398)
			(stroke
				(width 0)
				(type default)
			)
			(fill no)
			(layer "F.Fab")
		)
		(pad "1" smd custom
			(at 0 -0.4445 270)
			(size 0.1397 0.1397)
			(layers "F.Cu" "F.Mask" "F.Paste")
			(net "P3V3")
			(options
				(clearance outline)
				(anchor circle)
			)
			(primitives
				(gr_poly
					(pts
						(arc
							(start -0.1778 -0.2794)
							(mid -0.249642 -0.249642)
							(end -0.2794 -0.1778)
						)
						(arc
							(start -0.2794 0.1778)
							(mid -0.249642 0.249642)
							(end -0.1778 0.2794)
						)
						(arc
							(start 0.1778 0.2794)
							(mid 0.249642 0.249642)
							(end 0.2794 0.1778)
						)
						(arc
							(start 0.2794 -0.1778)
							(mid 0.249642 -0.249642)
							(end 0.1778 -0.2794)
						)
					)
					(width 0)
					(fill yes)
				)
			)
		)
		(pad "2" smd custom
			(at 0 0.4445 270)
			(size 0.1397 0.1397)
			(layers "F.Cu" "F.Mask" "F.Paste")
			(net "SSD_PRSNT_NET4")
			(options
				(clearance outline)
				(anchor circle)
			)
			(primitives
				(gr_poly
					(pts
						(arc
							(start -0.1778 -0.2794)
							(mid -0.249642 -0.249642)
							(end -0.2794 -0.1778)
						)
						(arc
							(start -0.2794 0.1778)
							(mid -0.249642 0.249642)
							(end -0.1778 0.2794)
						)
						(arc
							(start 0.1778 0.2794)
							(mid 0.249642 0.249642)
							(end 0.2794 0.1778)
						)
						(arc
							(start 0.2794 -0.1778)
							(mid 0.249642 -0.249642)
							(end 0.1778 -0.2794)
						)
					)
					(width 0)
					(fill yes)
				)
			)
		)
	)
	(footprint ""
		(layer "F.Cu")
		(at 75.5904 -355.219)
		(property "Reference" "C9321"
			(at 0 0 0)
			(layer "F.SilkS")
			(hide yes)
			(effects
				(font
					(size 1.27 1.27)
				)
			)
		)
		(property "Value" "SCD1U25V3KX-GP"
			(at 0 -2.8194 0)
			(unlocked yes)
			(layer "F.Fab")
			(hide yes)
			(effects
				(font
					(size 1.016 1.016)
					(thickness 0.1524)
				)
			)
		)
		(property "Device Type" "C603H36"
			(at 0 -4.3434 0)
			(unlocked yes)
			(layer "F.Fab")
			(hide yes)
			(effects
				(font
					(size 1.016 1.016)
					(thickness 0.1524)
				)
			)
		)
		(duplicate_pad_numbers_are_jumpers no)
		(fp_line
			(start 0.508 0)
			(end -0.508 0)
			(stroke
				(width 0.2032)
				(type default)
			)
			(layer "F.SilkS")
		)
		(fp_rect
			(start -0.5842 1.3335)
			(end 0.5842 -1.3335)
			(stroke
				(width 0)
				(type default)
			)
			(fill no)
			(layer "F.CrtYd")
		)
		(fp_rect
			(start -0.5842 1.3335)
			(end 0.5842 -1.3335)
			(stroke
				(width 0)
				(type default)
			)
			(fill no)
			(layer "F.Fab")
		)
		(pad "1" smd custom
			(at 0 -0.762)
			(size 0.2159 0.2159)
			(layers "F.Cu" "F.Mask" "F.Paste")
			(net "P3V3")
			(options
				(clearance outline)
				(anchor circle)
			)
			(primitives
				(gr_poly
					(pts
						(arc
							(start -0.3302 -0.4318)
							(mid -0.402042 -0.402042)
							(end -0.4318 -0.3302)
						)
						(arc
							(start -0.4318 0.3302)
							(mid -0.402042 0.402042)
							(end -0.3302 0.4318)
						)
						(arc
							(start 0.3302 0.4318)
							(mid 0.402042 0.402042)
							(end 0.4318 0.3302)
						)
						(arc
							(start 0.4318 -0.3302)
							(mid 0.402042 -0.402042)
							(end 0.3302 -0.4318)
						)
					)
					(width 0)
					(fill yes)
				)
			)
		)
		(pad "2" smd custom
			(at 0 0.762)
			(size 0.2159 0.2159)
			(layers "F.Cu" "F.Mask" "F.Paste")
			(net "GND")
			(options
				(clearance outline)
				(anchor circle)
			)
			(primitives
				(gr_poly
					(pts
						(arc
							(start -0.3302 -0.4318)
							(mid -0.402042 -0.402042)
							(end -0.4318 -0.3302)
						)
						(arc
							(start -0.4318 0.3302)
							(mid -0.402042 0.402042)
							(end -0.3302 0.4318)
						)
						(arc
							(start 0.3302 0.4318)
							(mid 0.402042 0.402042)
							(end 0.4318 0.3302)
						)
						(arc
							(start 0.4318 -0.3302)
							(mid 0.402042 -0.402042)
							(end 0.3302 -0.4318)
						)
					)
					(width 0)
					(fill yes)
				)
			)
		)
	)
	(footprint ""
		(layer "F.Cu")
		(at 69.977 -454.66)
		(property "Reference" "R347"
			(at 0 0 0)
			(layer "F.SilkS")
			(hide yes)
			(effects
				(font
					(size 1.27 1.27)
				)
			)
		)
		(property "Value" "4K7R2F-GP"
			(at 0.064008 -3.993896 0)
			(unlocked yes)
			(layer "F.Fab")
			(hide yes)
			(effects
				(font
					(size 1.016 1.016)
					(thickness 0.1524)
				)
			)
		)
		(property "Device Type" "R402H16"
			(at 0.064008 -5.517896 0)
			(unlocked yes)
			(layer "F.Fab")
			(hide yes)
			(effects
				(font
					(size 1.016 1.016)
					(thickness 0.1524)
				)
			)
		)
		(duplicate_pad_numbers_are_jumpers no)
		(fp_line
			(start -0.508 -0.9398)
			(end -0.508 0.9398)
			(stroke
				(width 0.1524)
				(type default)
			)
			(layer "F.SilkS")
		)
		(fp_line
			(start 0.508 -0.9398)
			(end -0.508 -0.9398)
			(stroke
				(width 0.1524)
				(type default)
			)
			(layer "F.SilkS")
		)
		(fp_rect
			(start -0.508 0.9398)
			(end 0.508 -0.9398)
			(stroke
				(width 0)
				(type default)
			)
			(fill no)
			(layer "F.CrtYd")
		)
		(fp_rect
			(start -0.508 0.9398)
			(end 0.508 -0.9398)
			(stroke
				(width 0)
				(type default)
			)
			(fill no)
			(layer "F.Fab")
		)
		(pad "1" smd custom
			(at 0 -0.4445)
			(size 0.1397 0.1397)
			(layers "F.Cu" "F.Mask" "F.Paste")
			(net "P3V3")
			(options
				(clearance outline)
				(anchor circle)
			)
			(primitives
				(gr_poly
					(pts
						(arc
							(start -0.1778 -0.2794)
							(mid -0.249642 -0.249642)
							(end -0.2794 -0.1778)
						)
						(arc
							(start -0.2794 0.1778)
							(mid -0.249642 0.249642)
							(end -0.1778 0.2794)
						)
						(arc
							(start 0.1778 0.2794)
							(mid 0.249642 0.249642)
							(end 0.2794 0.1778)
						)
						(arc
							(start 0.2794 -0.1778)
							(mid 0.249642 -0.249642)
							(end 0.1778 -0.2794)
						)
					)
					(width 0)
					(fill yes)
				)
			)
		)
		(pad "2" smd custom
			(at 0 0.4445)
			(size 0.1397 0.1397)
			(layers "F.Cu" "F.Mask" "F.Paste")
			(net "EEPROM_A2")
			(options
				(clearance outline)
				(anchor circle)
			)
			(primitives
				(gr_poly
					(pts
						(arc
							(start -0.1778 -0.2794)
							(mid -0.249642 -0.249642)
							(end -0.2794 -0.1778)
						)
						(arc
							(start -0.2794 0.1778)
							(mid -0.249642 0.249642)
							(end -0.1778 0.2794)
						)
						(arc
							(start 0.1778 0.2794)
							(mid 0.249642 0.249642)
							(end 0.2794 0.1778)
						)
						(arc
							(start 0.2794 -0.1778)
							(mid 0.249642 -0.249642)
							(end 0.1778 -0.2794)
						)
					)
					(width 0)
					(fill yes)
				)
			)
		)
	)
)
